(kicad_pcb
	(version 20241229)
	(generator "pcbnew")
	(generator_version "9.0")
	(general
		(thickness 1.62)
		(legacy_teardrops no)
	)
	(paper "A3")
	(title_block
		(title "COM Express 7 Baseboard")
		(date "2025-02-04")
		(rev "1.1.2")
		(company "Antmicro Ltd")
		(comment 1 "www.antmicro.com")
		(comment 9 "footprints 274-274 of 802")
	)
	(layers
		(0 "F.Cu" signal)
		(4 "In1.Cu" signal)
		(6 "In2.Cu" signal)
		(8 "In3.Cu" signal)
		(10 "In4.Cu" signal)
		(12 "In5.Cu" signal)
		(14 "In6.Cu" signal)
		(2 "B.Cu" signal)
		(9 "F.Adhes" user "F.Adhesive")
		(11 "B.Adhes" user "B.Adhesive")
		(13 "F.Paste" user)
		(15 "B.Paste" user)
		(5 "F.SilkS" user "F.Silkscreen")
		(7 "B.SilkS" user "B.Silkscreen")
		(1 "F.Mask" user)
		(3 "B.Mask" user)
		(17 "Dwgs.User" user "User.Drawings")
		(19 "Cmts.User" user "User.Comments")
		(21 "Eco1.User" user "User.Eco1")
		(23 "Eco2.User" user "User.Eco2")
		(25 "Edge.Cuts" user)
		(27 "Margin" user)
		(31 "F.CrtYd" user "F.Courtyard")
		(29 "B.CrtYd" user "B.Courtyard")
		(35 "F.Fab" user)
		(33 "B.Fab" user)
	)
	(footprint "antmicro-footprints:USB-C_Receptacle_Kycon_KUSBX-SL2-CS1N24-B-TR"
		(layer "F.Cu")
		(at 98.575 84.947 -90)
		(descr "USB-C (USB TYPE-C) USB 3.2 Gen 2 (USB 3.1 Gen 2, Superspeed + (USB 3.1)) Receptacle Connector 24 Position Through Hole, Right Angle")
		(tags "CONNECTOR, USB")
		(property "Reference" "J3"
			(at 4.013 -2.675 180)
			(layer "F.SilkS")
			(effects
				(font
					(size 0.7 0.7)
					(thickness 0.15)
				)
				(justify right bottom)
			)
		)
		(property "Value" "USB-C_Kycon_KUSBX-SL2-CS1N24-B-TR"
			(at 0 7.5 90)
			(layer "F.Fab")
			(effects
				(font
					(size 0.7 0.7)
					(thickness 0.15)
				)
				(justify left bottom)
			)
		)
		(property "Datasheet" "https://www.kycon.com/Pub_Eng_Draw/KUSBX-SL2-CS1N24-B-TR.pdf"
			(at 0 0 270)
			(layer "F.Fab")
			(hide yes)
			(effects
				(font
					(size 1.27 1.27)
					(thickness 0.15)
				)
			)
		)
		(property "Author" "Antmicro"
			(at 13.628 183.522 0)
			(layer "F.Fab")
			(hide yes)
			(effects
				(font
					(size 1 1)
					(thickness 0.15)
				)
			)
		)
		(property "License" "Apache-2.0"
			(at 13.628 183.522 0)
			(layer "F.Fab")
			(hide yes)
			(effects
				(font
					(size 1 1)
					(thickness 0.15)
				)
			)
		)
		(property "MPN" "KUSBX-SL2-CS1N24-B-TR"
			(at 13.628 183.522 0)
			(layer "F.Fab")
			(hide yes)
			(effects
				(font
					(size 1 1)
					(thickness 0.15)
				)
			)
		)
		(property "Manufacturer" "Kycon"
			(at 13.628 183.522 0)
			(layer "F.Fab")
			(hide yes)
			(effects
				(font
					(size 1 1)
					(thickness 0.15)
				)
			)
		)
		(sheetname "USB-C console")
		(sheetfile "usb-c_console.kicad_sch")
		(attr smd)
		(fp_line
			(start -1 -8.8)
			(end -1 -8.8)
			(stroke
				(width 0.15)
				(type solid)
			)
			(layer "F.SilkS")
		)
		(fp_line
			(start -1 -8.8)
			(end 1 -8.8)
			(stroke
				(width 0.15)
				(type solid)
			)
			(layer "F.SilkS")
		)
		(fp_line
			(start 1 -8.8)
			(end -1 -8.8)
			(stroke
				(width 0.15)
				(type solid)
			)
			(layer "F.SilkS")
		)
		(fp_line
			(start 1 -8.8)
			(end 1 -8.8)
			(stroke
				(width 0.15)
				(type solid)
			)
			(layer "F.SilkS")
		)
		(fp_rect
			(start -4 -9.4)
			(end 4 5.65)
			(stroke
				(width 0.05)
				(type solid)
			)
			(fill no)
			(layer "F.CrtYd")
		)
		(fp_line
			(start -2.25 5.5)
			(end 2.25 5.5)
			(stroke
				(width 0.15)
				(type solid)
			)
			(layer "F.Fab")
		)
		(fp_line
			(start 2.25 5.5)
			(end 2.25 -8.8)
			(stroke
				(width 0.15)
				(type solid)
			)
			(layer "F.Fab")
		)
		(fp_line
			(start -2.25 -8.8)
			(end -2.25 5.5)
			(stroke
				(width 0.15)
				(type solid)
			)
			(layer "F.Fab")
		)
		(fp_line
			(start 2.25 -8.8)
			(end -2.25 -8.8)
			(stroke
				(width 0.15)
				(type solid)
			)
			(layer "F.Fab")
		)
		(pad "" np_thru_hole circle
			(at 0 -7.6 270)
			(size 1.1 1.1)
			(drill 1.1)
			(layers "F&B.Cu" "*.Mask")
		)
		(pad "" np_thru_hole circle
			(at 0 0 270)
			(size 1 1)
			(drill 1)
			(layers "F&B.Cu" "*.Mask")
		)
		(pad "A1" smd rect
			(at 1.1375 -6.525)
			(size 0.25 1.625)
			(layers "F.Cu" "F.Mask" "F.Paste")
			(net 1 "GND")
			(pinfunction "GND")
			(pintype "power_in")
			(teardrops
				(best_length_ratio 0.2)
				(max_length 1)
				(best_width_ratio 0.9)
				(max_width 2)
				(curved_edges yes)
				(filter_ratio 0.9)
				(enabled yes)
				(allow_two_segments yes)
				(prefer_zone_connections yes)
			)
		)
		(pad "A2" smd rect
			(at 1.1375 -6.025)
			(size 0.25 1.625)
			(layers "F.Cu" "F.Mask" "F.Paste")
			(net 174 "unconnected-(J3-TX_{1}+-PadA2)")
			(pinfunction "TX_{1}+")
			(pintype "bidirectional+no_connect")
			(teardrops
				(best_length_ratio 0.2)
				(max_length 1)
				(best_width_ratio 0.9)
				(max_width 2)
				(curved_edges yes)
				(filter_ratio 0.9)
				(enabled yes)
				(allow_two_segments yes)
				(prefer_zone_connections yes)
			)
		)
		(pad "A3" smd rect
			(at 1.1375 -5.525)
			(size 0.25 1.625)
			(layers "F.Cu" "F.Mask" "F.Paste")
			(net 175 "unconnected-(J3-TX_{1}--PadA3)")
			(pinfunction "TX_{1}-")
			(pintype "bidirectional+no_connect")
			(teardrops
				(best_length_ratio 0.2)
				(max_length 1)
				(best_width_ratio 0.9)
				(max_width 2)
				(curved_edges yes)
				(filter_ratio 0.9)
				(enabled yes)
				(allow_two_segments yes)
				(prefer_zone_connections yes)
			)
		)
		(pad "A4" smd rect
			(at 1.1375 -5.025)
			(size 0.25 1.625)
			(layers "F.Cu" "F.Mask" "F.Paste")
			(net 58 "/USB-C console/VBUS_FTDI")
			(pinfunction "VBUS")
			(pintype "passive")
			(teardrops
				(best_length_ratio 0.2)
				(max_length 1)
				(best_width_ratio 0.9)
				(max_width 2)
				(curved_edges yes)
				(filter_ratio 0.9)
				(enabled yes)
				(allow_two_segments yes)
				(prefer_zone_connections yes)
			)
		)
		(pad "A5" smd rect
			(at 1.1375 -4.525)
			(size 0.25 1.625)
			(layers "F.Cu" "F.Mask" "F.Paste")
			(net 176 "Net-(J3-CC_{1})")
			(pinfunction "CC_{1}")
			(pintype "bidirectional")
			(teardrops
				(best_length_ratio 0.2)
				(max_length 1)
				(best_width_ratio 0.9)
				(max_width 2)
				(curved_edges yes)
				(filter_ratio 0.9)
				(enabled yes)
				(allow_two_segments yes)
				(prefer_zone_connections yes)
			)
		)
		(pad "A6" smd rect
			(at 1.1375 -4.025)
			(size 0.25 1.625)
			(layers "F.Cu" "F.Mask" "F.Paste")
			(net 55 "/USB-C console/USB_D+")
			(pinfunction "D_{A}+")
			(pintype "bidirectional")
			(teardrops
				(best_length_ratio 0.2)
				(max_length 1)
				(best_width_ratio 0.9)
				(max_width 2)
				(curved_edges yes)
				(filter_ratio 0.9)
				(enabled yes)
				(allow_two_segments yes)
				(prefer_zone_connections yes)
			)
		)
		(pad "A7" smd rect
			(at 1.1375 -3.525)
			(size 0.25 1.625)
			(layers "F.Cu" "F.Mask" "F.Paste")
			(net 56 "/USB-C console/USB_D-")
			(pinfunction "D_{A}-")
			(pintype "bidirectional")
			(teardrops
				(best_length_ratio 0.2)
				(max_length 1)
				(best_width_ratio 0.9)
				(max_width 2)
				(curved_edges yes)
				(filter_ratio 0.9)
				(enabled yes)
				(allow_two_segments yes)
				(prefer_zone_connections yes)
			)
		)
		(pad "A8" smd rect
			(at 1.1375 -3.025)
			(size 0.25 1.625)
			(layers "F.Cu" "F.Mask" "F.Paste")
			(net 177 "unconnected-(J3-SBU_{1}-PadA8)")
			(pinfunction "SBU_{1}")
			(pintype "bidirectional+no_connect")
			(teardrops
				(best_length_ratio 0.2)
				(max_length 1)
				(best_width_ratio 0.9)
				(max_width 2)
				(curved_edges yes)
				(filter_ratio 0.9)
				(enabled yes)
				(allow_two_segments yes)
				(prefer_zone_connections yes)
			)
		)
		(pad "A9" smd rect
			(at 1.1375 -2.525)
			(size 0.25 1.625)
			(layers "F.Cu" "F.Mask" "F.Paste")
			(net 58 "/USB-C console/VBUS_FTDI")
			(pinfunction "VBUS")
			(pintype "passive")
			(teardrops
				(best_length_ratio 0.2)
				(max_length 1)
				(best_width_ratio 0.9)
				(max_width 2)
				(curved_edges yes)
				(filter_ratio 0.9)
				(enabled yes)
				(allow_two_segments yes)
				(prefer_zone_connections yes)
			)
		)
		(pad "A10" smd rect
			(at 1.1375 -2.025)
			(size 0.25 1.625)
			(layers "F.Cu" "F.Mask" "F.Paste")
			(net 178 "unconnected-(J3-RX_{2}--PadA10)")
			(pinfunction "RX_{2}-")
			(pintype "bidirectional+no_connect")
			(teardrops
				(best_length_ratio 0.2)
				(max_length 1)
				(best_width_ratio 0.9)
				(max_width 2)
				(curved_edges yes)
				(filter_ratio 0.9)
				(enabled yes)
				(allow_two_segments yes)
				(prefer_zone_connections yes)
			)
		)
		(pad "A11" smd rect
			(at 1.1375 -1.525)
			(size 0.25 1.625)
			(layers "F.Cu" "F.Mask" "F.Paste")
			(net 179 "unconnected-(J3-RX_{2}+-PadA11)")
			(pinfunction "RX_{2}+")
			(pintype "bidirectional+no_connect")
			(teardrops
				(best_length_ratio 0.2)
				(max_length 1)
				(best_width_ratio 0.9)
				(max_width 2)
				(curved_edges yes)
				(filter_ratio 0.9)
				(enabled yes)
				(allow_two_segments yes)
				(prefer_zone_connections yes)
			)
		)
		(pad "A12" smd rect
			(at 1.1375 -1.025)
			(size 0.25 1.625)
			(layers "F.Cu" "F.Mask" "F.Paste")
			(net 1 "GND")
			(pinfunction "GND")
			(pintype "passive")
			(teardrops
				(best_length_ratio 0.2)
				(max_length 1)
				(best_width_ratio 0.9)
				(max_width 2)
				(curved_edges yes)
				(filter_ratio 0.9)
				(enabled yes)
				(allow_two_segments yes)
				(prefer_zone_connections yes)
			)
		)
		(pad "B1" smd rect
			(at -1.1375 -1.025)
			(size 0.25 1.625)
			(layers "F.Cu" "F.Mask" "F.Paste")
			(net 1 "GND")
			(pinfunction "GND")
			(pintype "passive")
			(teardrops
				(best_length_ratio 0.2)
				(max_length 1)
				(best_width_ratio 0.9)
				(max_width 2)
				(curved_edges yes)
				(filter_ratio 0.9)
				(enabled yes)
				(allow_two_segments yes)
				(prefer_zone_connections yes)
			)
		)
		(pad "B2" smd rect
			(at -1.1375 -1.525)
			(size 0.25 1.625)
			(layers "F.Cu" "F.Mask" "F.Paste")
			(net 180 "unconnected-(J3-TX_{2}+-PadB2)")
			(pinfunction "TX_{2}+")
			(pintype "bidirectional+no_connect")
			(teardrops
				(best_length_ratio 0.2)
				(max_length 1)
				(best_width_ratio 0.9)
				(max_width 2)
				(curved_edges yes)
				(filter_ratio 0.9)
				(enabled yes)
				(allow_two_segments yes)
				(prefer_zone_connections yes)
			)
		)
		(pad "B3" smd rect
			(at -1.1375 -2.025)
			(size 0.25 1.625)
			(layers "F.Cu" "F.Mask" "F.Paste")
			(net 181 "unconnected-(J3-TX_{2}--PadB3)")
			(pinfunction "TX_{2}-")
			(pintype "bidirectional+no_connect")
			(teardrops
				(best_length_ratio 0.2)
				(max_length 1)
				(best_width_ratio 0.9)
				(max_width 2)
				(curved_edges yes)
				(filter_ratio 0.9)
				(enabled yes)
				(allow_two_segments yes)
				(prefer_zone_connections yes)
			)
		)
		(pad "B4" smd rect
			(at -1.1375 -2.525)
			(size 0.25 1.625)
			(layers "F.Cu" "F.Mask" "F.Paste")
			(net 58 "/USB-C console/VBUS_FTDI")
			(pinfunction "VBUS")
			(pintype "passive")
			(teardrops
				(best_length_ratio 0.2)
				(max_length 1)
				(best_width_ratio 0.9)
				(max_width 2)
				(curved_edges yes)
				(filter_ratio 0.9)
				(enabled yes)
				(allow_two_segments yes)
				(prefer_zone_connections yes)
			)
		)
		(pad "B5" smd rect
			(at -1.1375 -3.025)
			(size 0.25 1.625)
			(layers "F.Cu" "F.Mask" "F.Paste")
			(net 182 "Net-(J3-CC_{2})")
			(pinfunction "CC_{2}")
			(pintype "bidirectional")
			(teardrops
				(best_length_ratio 0.2)
				(max_length 1)
				(best_width_ratio 0.9)
				(max_width 2)
				(curved_edges yes)
				(filter_ratio 0.9)
				(enabled yes)
				(allow_two_segments yes)
				(prefer_zone_connections yes)
			)
		)
		(pad "B6" smd rect
			(at -1.1375 -3.525)
			(size 0.25 1.625)
			(layers "F.Cu" "F.Mask" "F.Paste")
			(net 55 "/USB-C console/USB_D+")
			(pinfunction "D_{B}+")
			(pintype "bidirectional")
			(teardrops
				(best_length_ratio 0.2)
				(max_length 1)
				(best_width_ratio 0.9)
				(max_width 2)
				(curved_edges yes)
				(filter_ratio 0.9)
				(enabled yes)
				(allow_two_segments yes)
				(prefer_zone_connections yes)
			)
		)
		(pad "B7" smd rect
			(at -1.1375 -4.025)
			(size 0.25 1.625)
			(layers "F.Cu" "F.Mask" "F.Paste")
			(net 56 "/USB-C console/USB_D-")
			(pinfunction "D_{B}-")
			(pintype "bidirectional")
			(teardrops
				(best_length_ratio 0.2)
				(max_length 1)
				(best_width_ratio 0.9)
				(max_width 2)
				(curved_edges yes)
				(filter_ratio 0.9)
				(enabled yes)
				(allow_two_segments yes)
				(prefer_zone_connections yes)
			)
		)
		(pad "B8" smd rect
			(at -1.1375 -4.525)
			(size 0.25 1.625)
			(layers "F.Cu" "F.Mask" "F.Paste")
			(net 183 "unconnected-(J3-SBU_{2}-PadB8)")
			(pinfunction "SBU_{2}")
			(pintype "bidirectional+no_connect")
			(teardrops
				(best_length_ratio 0.2)
				(max_length 1)
				(best_width_ratio 0.9)
				(max_width 2)
				(curved_edges yes)
				(filter_ratio 0.9)
				(enabled yes)
				(allow_two_segments yes)
				(prefer_zone_connections yes)
			)
		)
		(pad "B9" smd rect
			(at -1.1375 -5.025)
			(size 0.25 1.625)
			(layers "F.Cu" "F.Mask" "F.Paste")
			(net 58 "/USB-C console/VBUS_FTDI")
			(pinfunction "VBUS")
			(pintype "passive")
			(teardrops
				(best_length_ratio 0.2)
				(max_length 1)
				(best_width_ratio 0.9)
				(max_width 2)
				(curved_edges yes)
				(filter_ratio 0.9)
				(enabled yes)
				(allow_two_segments yes)
				(prefer_zone_connections yes)
			)
		)
		(pad "B10" smd rect
			(at -1.1375 -5.525)
			(size 0.25 1.625)
			(layers "F.Cu" "F.Mask" "F.Paste")
			(net 184 "unconnected-(J3-RX_{1}--PadB10)")
			(pinfunction "RX_{1}-")
			(pintype "bidirectional+no_connect")
			(teardrops
				(best_length_ratio 0.2)
				(max_length 1)
				(best_width_ratio 0.9)
				(max_width 2)
				(curved_edges yes)
				(filter_ratio 0.9)
				(enabled yes)
				(allow_two_segments yes)
				(prefer_zone_connections yes)
			)
		)
		(pad "B11" smd rect
			(at -1.1375 -6.025)
			(size 0.25 1.625)
			(layers "F.Cu" "F.Mask" "F.Paste")
			(net 185 "unconnected-(J3-RX_{1}+-PadB11)")
			(pinfunction "RX_{1}+")
			(pintype "bidirectional+no_connect")
			(teardrops
				(best_length_ratio 0.2)
				(max_length 1)
				(best_width_ratio 0.9)
				(max_width 2)
				(curved_edges yes)
				(filter_ratio 0.9)
				(enabled yes)
				(allow_two_segments yes)
				(prefer_zone_connections yes)
			)
		)
		(pad "B12" smd rect
			(at -1.1375 -6.525)
			(size 0.25 1.625)
			(layers "F.Cu" "F.Mask" "F.Paste")
			(net 1 "GND")
			(pinfunction "GND")
			(pintype "passive")
			(teardrops
				(best_length_ratio 0.2)
				(max_length 1)
				(best_width_ratio 0.9)
				(max_width 2)
				(curved_edges yes)
				(filter_ratio 0.9)
				(enabled yes)
				(allow_two_segments yes)
				(prefer_zone_connections yes)
			)
		)
		(pad "SH" thru_hole oval
			(at -3 -7.849 270)
			(size 1 2.05)
			(drill oval 0.6 1.65)
			(layers "*.Cu" "*.Mask")
			(remove_unused_layers no)
			(net 54 "/USB-C console/SH")
			(pinfunction "SH")
			(pintype "passive")
			(teardrops
				(best_length_ratio 0.2)
				(max_length 1)
				(best_width_ratio 0.9)
				(max_width 2)
				(curved_edges yes)
				(filter_ratio 0.9)
				(enabled yes)
				(allow_two_segments yes)
				(prefer_zone_connections yes)
			)
		)
		(pad "SH" thru_hole oval
			(at -3 0.25 270)
			(size 1 2.05)
			(drill oval 0.6 1.65)
			(layers "*.Cu" "*.Mask")
			(remove_unused_layers no)
			(net 54 "/USB-C console/SH")
			(pinfunction "SH")
			(pintype "passive")
			(teardrops
				(best_length_ratio 0.2)
				(max_length 1)
				(best_width_ratio 0.9)
				(max_width 2)
				(curved_edges yes)
				(filter_ratio 0.9)
				(enabled yes)
				(allow_two_segments yes)
				(prefer_zone_connections yes)
			)
		)
		(pad "SH" thru_hole oval
			(at 3 -7.849 270)
			(size 1 2.05)
			(drill oval 0.6 1.65)
			(layers "*.Cu" "*.Mask")
			(remove_unused_layers no)
			(net 54 "/USB-C console/SH")
			(pinfunction "SH")
			(pintype "passive")
			(teardrops
				(best_length_ratio 0.2)
				(max_length 1)
				(best_width_ratio 0.9)
				(max_width 2)
				(curved_edges yes)
				(filter_ratio 0.9)
				(enabled yes)
				(allow_two_segments yes)
				(prefer_zone_connections yes)
			)
		)
		(pad "SH" thru_hole oval
			(at 3 0.25 270)
			(size 1 2.05)
			(drill oval 0.6 1.65)
			(layers "*.Cu" "*.Mask")
			(remove_unused_layers no)
			(net 54 "/USB-C console/SH")
			(pinfunction "SH")
			(pintype "passive")
			(teardrops
				(best_length_ratio 0.2)
				(max_length 1)
				(best_width_ratio 0.9)
				(max_width 2)
				(curved_edges yes)
				(filter_ratio 0.9)
				(enabled yes)
				(allow_two_segments yes)
				(prefer_zone_connections yes)
			)
		)
	)
)
